# S9S_MB_2U (Grand Teton) — schematic netlist excerpt (pin names and nets, part order shuffled) for the footprints in the layout excerpt that follows; sources: Cadence DE-HDL packaged netlist, KiCad conversion of 03242023_DA0F0TMBIJ0_F0T_Motherboard_J_brd_V01_OCP.brd

R1763  Q_RES  10K 1% EMPTY  pkg 0402LF  page 257 : A = PGPPA_AUX ; B = FM_LPC_ESPI_SEL
R964  Q_RES  240 1% CHIP  pkg 0402LF  page 235 : A = PVNN_TERM_CPU1 ; B = SMB_PEHPCPU1_GTL_R_SDA

(kicad_pcb
	(version 20260206)
	(generator "pcbnew")
	(generator_version "10.0")
	(general
		(thickness 1.6)
		(legacy_teardrops no)
	)
	(paper "A4")
	(title_block
		(title "03242023_DA0F0TMBIJ0_F0T_Motherboard_J_brd_V01_OCP.brd")
		(comment 1 "Grand Teton / footprints 5813-5814 of 6105")
	)
	(layers
		(0 "F.Cu" signal "TOP")
		(4 "In1.Cu" signal "GND")
		(6 "In2.Cu" signal "IN1")
		(8 "In3.Cu" signal "GND1")
		(10 "In4.Cu" signal "IN2")
		(12 "In5.Cu" signal "GND2")
		(14 "In6.Cu" signal "IN3")
		(16 "In7.Cu" signal "GND3")
		(18 "In8.Cu" signal "VCC")
		(20 "In9.Cu" signal "VCC1")
		(22 "In10.Cu" signal "GND4")
		(24 "In11.Cu" signal "IN4")
		(26 "In12.Cu" signal "GND5")
		(28 "In13.Cu" signal "IN5")
		(30 "In14.Cu" signal "GND6")
		(32 "In15.Cu" signal "IN6")
		(34 "In16.Cu" signal "GND7")
		(2 "B.Cu" signal "BOTTOM")
		(9 "F.Adhes" user "F.Adhesive")
		(11 "B.Adhes" user "B.Adhesive")
		(13 "F.Paste" user "Package Geometry/Pastemask Top")
		(15 "B.Paste" user "Package Geometry/Pastemask Bottom")
		(5 "F.SilkS" user "Ref Des/Silkscreen Top")
		(7 "B.SilkS" user "Ref Des/Silkscreen Bottom")
		(1 "F.Mask" user "Board Geometry/Soldermask Top")
		(3 "B.Mask" user "Board Geometry/Soldermask Bottom")
		(17 "Dwgs.User" user "User.Drawings")
		(19 "Cmts.User" user "User.Comments")
		(21 "Eco1.User" user "User.Eco1")
		(23 "Eco2.User" user "User.Eco2")
		(25 "Edge.Cuts" user "Board Geometry/Outline")
		(27 "Margin" user)
		(31 "F.CrtYd" user "Package Geometry/Place Bound Top")
		(29 "B.CrtYd" user "Package Geometry/Place Bound Bottom")
		(35 "F.Fab" user "Ref Des/Assembly Top")
		(33 "B.Fab" user "Ref Des/Assembly Bottom")
	)
	(footprint ""
		(layer "B.Cu")
		(at 17.725136 -191.700404)
		(property "Reference" "R964"
			(at 0 0 0)
			(layer "B.SilkS")
			(hide yes)
			(effects
				(font
					(size 1.27 1.27)
				)
				(justify mirror)
			)
		)
		(property "Value" ""
			(at 0 0 0)
			(layer "B.Fab")
			(effects
				(font
					(size 1.27 1.27)
				)
				(justify mirror)
			)
		)
		(duplicate_pad_numbers_are_jumpers no)
		(fp_line
			(start -0.7874 -0.4064)
			(end -0.7874 0.4064)
			(stroke
				(width 0.1524)
				(type default)
			)
			(layer "B.SilkS")
		)
		(fp_line
			(start -0.7874 0.4064)
			(end 0.7874 0.4064)
			(stroke
				(width 0.1524)
				(type default)
			)
			(layer "B.SilkS")
		)
		(fp_line
			(start 0.7874 -0.4064)
			(end -0.7874 -0.4064)
			(stroke
				(width 0.1524)
				(type default)
			)
			(layer "B.SilkS")
		)
		(fp_line
			(start 0.7874 0.4064)
			(end 0.7874 -0.4064)
			(stroke
				(width 0.1524)
				(type default)
			)
			(layer "B.SilkS")
		)
		(fp_line
			(start -0.67945 -0.3048)
			(end -0.67945 0.3048)
			(stroke
				(width 0.1)
				(type default)
			)
			(layer "B.Fab")
		)
		(fp_line
			(start -0.67945 0.3048)
			(end -0.120396 0.3048)
			(stroke
				(width 0.1)
				(type default)
			)
			(layer "B.Fab")
		)
		(fp_line
			(start -0.12065 -0.3048)
			(end -0.67945 -0.3048)
			(stroke
				(width 0.1)
				(type default)
			)
			(layer "B.Fab")
		)
		(fp_line
			(start -0.12065 -0.2794)
			(end -0.12065 -0.3048)
			(stroke
				(width 0.1)
				(type default)
			)
			(layer "B.Fab")
		)
		(fp_line
			(start -0.120396 0.2794)
			(end 0.12065 0.2794)
			(stroke
				(width 0.1)
				(type default)
			)
			(layer "B.Fab")
		)
		(fp_line
			(start -0.120396 0.3048)
			(end -0.120396 0.2794)
			(stroke
				(width 0.1)
				(type default)
			)
			(layer "B.Fab")
		)
		(fp_line
			(start 0.12065 -0.305054)
			(end 0.12065 -0.2794)
			(stroke
				(width 0.1)
				(type default)
			)
			(layer "B.Fab")
		)
		(fp_line
			(start 0.12065 -0.2794)
			(end -0.12065 -0.2794)
			(stroke
				(width 0.1)
				(type default)
			)
			(layer "B.Fab")
		)
		(fp_line
			(start 0.12065 0.2794)
			(end 0.12065 0.3048)
			(stroke
				(width 0.1)
				(type default)
			)
			(layer "B.Fab")
		)
		(fp_line
			(start 0.12065 0.3048)
			(end 0.67945 0.3048)
			(stroke
				(width 0.1)
				(type default)
			)
			(layer "B.Fab")
		)
		(fp_line
			(start 0.67945 -0.305054)
			(end 0.12065 -0.305054)
			(stroke
				(width 0.1)
				(type default)
			)
			(layer "B.Fab")
		)
		(fp_line
			(start 0.67945 0.3048)
			(end 0.67945 -0.305054)
			(stroke
				(width 0.1)
				(type default)
			)
			(layer "B.Fab")
		)
		(pad "1" smd circle
			(at 0.40005 0 180)
			(size 0 0)
			(layers "B.Cu" "B.Mask" "B.Paste")
			(net "PVNN_TERM_CPU1")
		)
		(pad "2" smd circle
			(at -0.40005 0 180)
			(size 0 0)
			(layers "B.Cu" "B.Mask" "B.Paste")
			(net "SMB_PEHPCPU1_GTL_R_SDA")
		)
	)
	(footprint ""
		(layer "B.Cu")
		(at 173.377352 -22.564598 90)
		(property "Reference" "R1763"
			(at 0 0 90)
			(layer "B.SilkS")
			(hide yes)
			(effects
				(font
					(size 1.27 1.27)
				)
				(justify mirror)
			)
		)
		(property "Value" ""
			(at 0 0 90)
			(layer "B.Fab")
			(effects
				(font
					(size 1.27 1.27)
				)
				(justify mirror)
			)
		)
		(duplicate_pad_numbers_are_jumpers no)
		(fp_line
			(start 0.7874 -0.4064)
			(end -0.7874 -0.4064)
			(stroke
				(width 0.1524)
				(type default)
			)
			(layer "B.SilkS")
		)
		(fp_line
			(start -0.7874 -0.4064)
			(end -0.7874 0.4064)
			(stroke
				(width 0.1524)
				(type default)
			)
			(layer "B.SilkS")
		)
		(fp_line
			(start 0.7874 0.4064)
			(end 0.7874 -0.4064)
			(stroke
				(width 0.1524)
				(type default)
			)
			(layer "B.SilkS")
		)
		(fp_line
			(start -0.7874 0.4064)
			(end 0.7874 0.4064)
			(stroke
				(width 0.1524)
				(type default)
			)
			(layer "B.SilkS")
		)
		(fp_line
			(start 0.67945 -0.305054)
			(end 0.12065 -0.305054)
			(stroke
				(width 0.1)
				(type default)
			)
			(layer "B.Fab")
		)
		(fp_line
			(start 0.12065 -0.305054)
			(end 0.12065 -0.2794)
			(stroke
				(width 0.1)
				(type default)
			)
			(layer "B.Fab")
		)
		(fp_line
			(start -0.12065 -0.3048)
			(end -0.67945 -0.3048)
			(stroke
				(width 0.1)
				(type default)
			)
			(layer "B.Fab")
		)
		(fp_line
			(start -0.67945 -0.3048)
			(end -0.67945 0.3048)
			(stroke
				(width 0.1)
				(type default)
			)
			(layer "B.Fab")
		)
		(fp_line
			(start 0.12065 -0.2794)
			(end -0.12065 -0.2794)
			(stroke
				(width 0.1)
				(type default)
			)
			(layer "B.Fab")
		)
		(fp_line
			(start -0.12065 -0.2794)
			(end -0.12065 -0.3048)
			(stroke
				(width 0.1)
				(type default)
			)
			(layer "B.Fab")
		)
		(fp_line
			(start 0.12065 0.2794)
			(end 0.12065 0.3048)
			(stroke
				(width 0.1)
				(type default)
			)
			(layer "B.Fab")
		)
		(fp_line
			(start -0.120396 0.2794)
			(end 0.12065 0.2794)
			(stroke
				(width 0.1)
				(type default)
			)
			(layer "B.Fab")
		)
		(fp_line
			(start 0.67945 0.3048)
			(end 0.67945 -0.305054)
			(stroke
				(width 0.1)
				(type default)
			)
			(layer "B.Fab")
		)
		(fp_line
			(start 0.12065 0.3048)
			(end 0.67945 0.3048)
			(stroke
				(width 0.1)
				(type default)
			)
			(layer "B.Fab")
		)
		(fp_line
			(start -0.120396 0.3048)
			(end -0.120396 0.2794)
			(stroke
				(width 0.1)
				(type default)
			)
			(layer "B.Fab")
		)
		(fp_line
			(start -0.67945 0.3048)
			(end -0.120396 0.3048)
			(stroke
				(width 0.1)
				(type default)
			)
			(layer "B.Fab")
		)
		(pad "1" smd circle
			(at 0.40005 0 270)
			(size 0 0)
			(layers "B.Cu" "B.Mask" "B.Paste")
			(net "PGPPA_AUX")
		)
		(pad "2" smd circle
			(at -0.40005 0 270)
			(size 0 0)
			(layers "B.Cu" "B.Mask" "B.Paste")
			(net "FM_LPC_ESPI_SEL")
		)
	)
)
